(kicad_pcb
	(version 20260206)
	(generator "pcbnew")
	(generator_version "10.0")
	(general
		(thickness 1.6)
		(legacy_teardrops no)
	)
	(paper "A4")
	(title_block
		(title "panther-plus-userver — 13130-1b_20150205.brd")
		(comment 1 "Honey Badger (Wiwynn) / footprints 1056-1062 of 1509")
	)
	(layers
		(0 "F.Cu" signal "TOP")
		(4 "In1.Cu" signal "L2")
		(6 "In2.Cu" signal "L3")
		(8 "In3.Cu" signal "L4")
		(10 "In4.Cu" signal "L5")
		(12 "In5.Cu" signal "L6")
		(14 "In6.Cu" signal "L7")
		(16 "In7.Cu" signal "L8")
		(18 "In8.Cu" signal "L9")
		(20 "In9.Cu" signal "L10")
		(22 "In10.Cu" signal "L11")
		(2 "B.Cu" signal "BOTTOM")
		(9 "F.Adhes" user "F.Adhesive")
		(11 "B.Adhes" user "B.Adhesive")
		(13 "F.Paste" user "Package Geometry/Pastemask Top")
		(15 "B.Paste" user "Package Geometry/Pastemask Bottom")
		(5 "F.SilkS" user "Ref Des/Silkscreen Top")
		(7 "B.SilkS" user "Ref Des/Silkscreen Bottom")
		(1 "F.Mask" user "Board Geometry/Soldermask Top")
		(3 "B.Mask" user "Board Geometry/Soldermask Bottom")
		(17 "Dwgs.User" user "User.Drawings")
		(19 "Cmts.User" user "User.Comments")
		(21 "Eco1.User" user "User.Eco1")
		(23 "Eco2.User" user "User.Eco2")
		(25 "Edge.Cuts" user "Board Geometry/Outline")
		(27 "Margin" user)
		(31 "F.CrtYd" user "Package Geometry/Place Bound Top")
		(29 "B.CrtYd" user "Package Geometry/Place Bound Bottom")
		(35 "F.Fab" user "Ref Des/Assembly Top")
		(33 "B.Fab" user "Ref Des/Assembly Bottom")
	)
	(footprint ""
		(layer "B.Cu")
		(at 42.6466 -27.5336 180)
		(property "Reference" "R327"
			(at 0 0 0)
			(layer "B.SilkS")
			(hide yes)
			(effects
				(font
					(size 1.27 1.27)
				)
				(justify mirror)
			)
		)
		(property "Value" "33R2F-3-GP"
			(at -0.064008 -3.993896 180)
			(unlocked yes)
			(layer "B.Fab")
			(hide yes)
			(effects
				(font
					(size 1.016 1.016)
					(thickness 0.1524)
				)
				(justify mirror)
			)
		)
		(property "Device Type" "R402H16"
			(at -0.064008 -5.517896 180)
			(unlocked yes)
			(layer "B.Fab")
			(hide yes)
			(effects
				(font
					(size 1.016 1.016)
					(thickness 0.1524)
				)
				(justify mirror)
			)
		)
		(duplicate_pad_numbers_are_jumpers no)
		(fp_rect
			(start 0.381 0.8382)
			(end -0.381 -0.8382)
			(stroke
				(width 0)
				(type default)
			)
			(fill no)
			(layer "B.CrtYd")
		)
		(fp_rect
			(start 0.381 0.8382)
			(end -0.381 -0.8382)
			(stroke
				(width 0)
				(type default)
			)
			(fill no)
			(layer "B.Fab")
		)
		(pad "1" smd custom
			(at 0 -0.4318)
			(size 0.127 0.127)
			(layers "B.Cu" "B.Mask" "B.Paste")
			(net "CLK_100M_CLKBUFF_PCIE_R_DP")
			(options
				(clearance outline)
				(anchor circle)
			)
			(primitives
				(gr_poly
					(pts
						(arc
							(start -0.2032 0.2794)
							(mid -0.239121 0.264521)
							(end -0.254 0.2286)
						)
						(arc
							(start -0.254 -0.2286)
							(mid -0.239121 -0.264521)
							(end -0.2032 -0.2794)
						)
						(arc
							(start 0.2032 -0.2794)
							(mid 0.239121 -0.264521)
							(end 0.254 -0.2286)
						)
						(arc
							(start 0.254 0.2286)
							(mid 0.239121 0.264521)
							(end 0.2032 0.2794)
						)
					)
					(width 0)
					(fill yes)
				)
			)
		)
		(pad "2" smd custom
			(at 0 0.4318)
			(size 0.127 0.127)
			(layers "B.Cu" "B.Mask" "B.Paste")
			(net "CLK_100M_CLKBUFF_PCIE_DP")
			(options
				(clearance outline)
				(anchor circle)
			)
			(primitives
				(gr_poly
					(pts
						(arc
							(start -0.2032 0.2794)
							(mid -0.239121 0.264521)
							(end -0.254 0.2286)
						)
						(arc
							(start -0.254 -0.2286)
							(mid -0.239121 -0.264521)
							(end -0.2032 -0.2794)
						)
						(arc
							(start 0.2032 -0.2794)
							(mid 0.239121 -0.264521)
							(end 0.254 -0.2286)
						)
						(arc
							(start 0.254 0.2286)
							(mid 0.239121 0.264521)
							(end 0.2032 0.2794)
						)
					)
					(width 0)
					(fill yes)
				)
			)
		)
	)
	(footprint ""
		(layer "B.Cu")
		(at 39.878 -51.943 180)
		(property "Reference" "C67"
			(at 0 0 0)
			(layer "B.SilkS")
			(hide yes)
			(effects
				(font
					(size 1.27 1.27)
				)
				(justify mirror)
			)
		)
		(property "Value" "SC10U6D3V3MX-GP"
			(at 0.0254 -2.0193 180)
			(unlocked yes)
			(layer "B.Fab")
			(hide yes)
			(effects
				(font
					(size 1.016 1.016)
					(thickness 0.1524)
				)
				(justify mirror)
			)
		)
		(property "Device Type" "C603H38"
			(at 0.0254 -3.5433 180)
			(unlocked yes)
			(layer "B.Fab")
			(hide yes)
			(effects
				(font
					(size 1.016 1.016)
					(thickness 0.1524)
				)
				(justify mirror)
			)
		)
		(duplicate_pad_numbers_are_jumpers no)
		(fp_line
			(start 0.4064 0)
			(end -0.4064 0)
			(stroke
				(width 0.2286)
				(type default)
			)
			(layer "B.SilkS")
		)
		(fp_rect
			(start 0.635 1.1811)
			(end -0.635 -1.1811)
			(stroke
				(width 0)
				(type default)
			)
			(fill no)
			(layer "B.CrtYd")
		)
		(fp_rect
			(start 0.635 1.1811)
			(end -0.635 -1.1811)
			(stroke
				(width 0)
				(type default)
			)
			(fill no)
			(layer "B.Fab")
		)
		(pad "1" smd custom
			(at 0 -0.6604)
			(size 0.19685 0.19685)
			(layers "B.Cu" "B.Mask" "B.Paste")
			(net "P3V3_CLK_PCI")
			(options
				(clearance outline)
				(anchor circle)
			)
			(primitives
				(gr_poly
					(pts
						(arc
							(start 0.508 0.2921)
							(mid 0.478242 0.363942)
							(end 0.4064 0.3937)
						)
						(arc
							(start -0.4064 0.3937)
							(mid -0.478242 0.363942)
							(end -0.508 0.2921)
						)
						(arc
							(start -0.508 -0.2921)
							(mid -0.478242 -0.363942)
							(end -0.4064 -0.3937)
						)
						(arc
							(start 0.4064 -0.3937)
							(mid 0.478242 -0.363942)
							(end 0.508 -0.2921)
						)
					)
					(width 0)
					(fill yes)
				)
			)
		)
		(pad "2" smd custom
			(at 0 0.6604)
			(size 0.19685 0.19685)
			(layers "B.Cu" "B.Mask" "B.Paste")
			(net "GND")
			(options
				(clearance outline)
				(anchor circle)
			)
			(primitives
				(gr_poly
					(pts
						(arc
							(start 0.508 0.2921)
							(mid 0.478242 0.363942)
							(end 0.4064 0.3937)
						)
						(arc
							(start -0.4064 0.3937)
							(mid -0.478242 0.363942)
							(end -0.508 0.2921)
						)
						(arc
							(start -0.508 -0.2921)
							(mid -0.478242 -0.363942)
							(end -0.4064 -0.3937)
						)
						(arc
							(start 0.4064 -0.3937)
							(mid 0.478242 -0.363942)
							(end 0.508 -0.2921)
						)
					)
					(width 0)
					(fill yes)
				)
			)
		)
	)
	(footprint ""
		(layer "B.Cu")
		(at 94.361 -52.197)
		(property "Reference" "L5"
			(at 0 0 0)
			(layer "B.SilkS")
			(hide yes)
			(effects
				(font
					(size 1.27 1.27)
				)
				(justify mirror)
			)
		)
		(property "Value" "BLM18PG121SN1D-GP"
			(at 0.0254 -2.8956 0)
			(unlocked yes)
			(layer "B.Fab")
			(hide yes)
			(effects
				(font
					(size 1.016 1.016)
					(thickness 0.1524)
				)
				(justify mirror)
			)
		)
		(property "Device Type" "L1608-UH38"
			(at 0.0254 -4.4196 0)
			(unlocked yes)
			(layer "B.Fab")
			(hide yes)
			(effects
				(font
					(size 1.016 1.016)
					(thickness 0.1524)
				)
				(justify mirror)
			)
		)
		(duplicate_pad_numbers_are_jumpers no)
		(fp_line
			(start 0.4064 0)
			(end -0.4064 0)
			(stroke
				(width 0.2032)
				(type default)
			)
			(layer "B.SilkS")
		)
		(fp_rect
			(start 0.635 1.1811)
			(end -0.635 -1.1811)
			(stroke
				(width 0)
				(type default)
			)
			(fill no)
			(layer "B.CrtYd")
		)
		(fp_rect
			(start 0.635 1.1811)
			(end -0.635 -1.1811)
			(stroke
				(width 0)
				(type default)
			)
			(fill no)
			(layer "B.Fab")
		)
		(pad "1" smd custom
			(at 0 -0.6604 180)
			(size 0.19685 0.19685)
			(layers "B.Cu" "B.Mask" "B.Paste")
			(net "P1V0")
			(options
				(clearance outline)
				(anchor circle)
			)
			(primitives
				(gr_poly
					(pts
						(arc
							(start 0.508 0.2921)
							(mid 0.478242 0.363942)
							(end 0.4064 0.3937)
						)
						(arc
							(start -0.4064 0.3937)
							(mid -0.478242 0.363942)
							(end -0.508 0.2921)
						)
						(arc
							(start -0.508 -0.2921)
							(mid -0.478242 -0.363942)
							(end -0.4064 -0.3937)
						)
						(arc
							(start 0.4064 -0.3937)
							(mid 0.478242 -0.363942)
							(end 0.508 -0.2921)
						)
					)
					(width 0)
					(fill yes)
				)
			)
		)
		(pad "2" smd custom
			(at 0 0.6604 180)
			(size 0.19685 0.19685)
			(layers "B.Cu" "B.Mask" "B.Paste")
			(net "VCCACKDDR0")
			(options
				(clearance outline)
				(anchor circle)
			)
			(primitives
				(gr_poly
					(pts
						(arc
							(start 0.508 0.2921)
							(mid 0.478242 0.363942)
							(end 0.4064 0.3937)
						)
						(arc
							(start -0.4064 0.3937)
							(mid -0.478242 0.363942)
							(end -0.508 0.2921)
						)
						(arc
							(start -0.508 -0.2921)
							(mid -0.478242 -0.363942)
							(end -0.4064 -0.3937)
						)
						(arc
							(start 0.4064 -0.3937)
							(mid 0.478242 -0.363942)
							(end 0.508 -0.2921)
						)
					)
					(width 0)
					(fill yes)
				)
			)
		)
	)
	(footprint ""
		(layer "B.Cu")
		(at 87.122 -30.099 180)
		(property "Reference" "R366"
			(at 0 0 0)
			(layer "B.SilkS")
			(hide yes)
			(effects
				(font
					(size 1.27 1.27)
				)
				(justify mirror)
			)
		)
		(property "Value" "100R3F-1-GP"
			(at 0.0254 -2.5146 180)
			(unlocked yes)
			(layer "B.Fab")
			(hide yes)
			(effects
				(font
					(size 1.016 1.016)
					(thickness 0.1524)
				)
				(justify mirror)
			)
		)
		(property "Device Type" "R603H22"
			(at 0.0254 -4.0386 180)
			(unlocked yes)
			(layer "B.Fab")
			(hide yes)
			(effects
				(font
					(size 1.016 1.016)
					(thickness 0.1524)
				)
				(justify mirror)
			)
		)
		(duplicate_pad_numbers_are_jumpers no)
		(fp_line
			(start 0.2032 0)
			(end 0.4191 0)
			(stroke
				(width 0.2032)
				(type default)
			)
			(layer "B.SilkS")
		)
		(fp_line
			(start -0.4318 0)
			(end -0.2032 0)
			(stroke
				(width 0.2032)
				(type default)
			)
			(layer "B.SilkS")
		)
		(fp_rect
			(start 0.635 1.1811)
			(end -0.635 -1.1811)
			(stroke
				(width 0)
				(type default)
			)
			(fill no)
			(layer "B.CrtYd")
		)
		(fp_rect
			(start 0.635 1.1811)
			(end -0.635 -1.1811)
			(stroke
				(width 0)
				(type default)
			)
			(fill no)
			(layer "B.Fab")
		)
		(pad "1" smd custom
			(at 0 -0.6604)
			(size 0.19685 0.19685)
			(layers "B.Cu" "B.Mask" "B.Paste")
			(net "SATA2_OBS_P")
			(options
				(clearance outline)
				(anchor circle)
			)
			(primitives
				(gr_poly
					(pts
						(arc
							(start 0.508 0.2921)
							(mid 0.478242 0.363942)
							(end 0.4064 0.3937)
						)
						(arc
							(start -0.4064 0.3937)
							(mid -0.478242 0.363942)
							(end -0.508 0.2921)
						)
						(arc
							(start -0.508 -0.2921)
							(mid -0.478242 -0.363942)
							(end -0.4064 -0.3937)
						)
						(arc
							(start 0.4064 -0.3937)
							(mid 0.478242 -0.363942)
							(end 0.508 -0.2921)
						)
					)
					(width 0)
					(fill yes)
				)
			)
		)
		(pad "2" smd custom
			(at 0 0.6604)
			(size 0.19685 0.19685)
			(layers "B.Cu" "B.Mask" "B.Paste")
			(net "SATA2_OBS_N")
			(options
				(clearance outline)
				(anchor circle)
			)
			(primitives
				(gr_poly
					(pts
						(arc
							(start 0.508 0.2921)
							(mid 0.478242 0.363942)
							(end 0.4064 0.3937)
						)
						(arc
							(start -0.4064 0.3937)
							(mid -0.478242 0.363942)
							(end -0.508 0.2921)
						)
						(arc
							(start -0.508 -0.2921)
							(mid -0.478242 -0.363942)
							(end -0.4064 -0.3937)
						)
						(arc
							(start 0.4064 -0.3937)
							(mid 0.478242 -0.363942)
							(end 0.508 -0.2921)
						)
					)
					(width 0)
					(fill yes)
				)
			)
		)
	)
	(footprint ""
		(layer "B.Cu")
		(at 188.468 -16.383)
		(property "Reference" "PC204"
			(at 0 0 0)
			(layer "B.SilkS")
			(hide yes)
			(effects
				(font
					(size 1.27 1.27)
				)
				(justify mirror)
			)
		)
		(property "Value" "SC10U6D3V3MX-GP"
			(at 0 -2.8194 0)
			(unlocked yes)
			(layer "B.Fab")
			(hide yes)
			(effects
				(font
					(size 1.016 1.016)
					(thickness 0.1524)
				)
				(justify mirror)
			)
		)
		(property "Device Type" "C603H38"
			(at 0 -4.3434 0)
			(unlocked yes)
			(layer "B.Fab")
			(hide yes)
			(effects
				(font
					(size 1.016 1.016)
					(thickness 0.1524)
				)
				(justify mirror)
			)
		)
		(duplicate_pad_numbers_are_jumpers no)
		(fp_line
			(start 0.4064 0)
			(end -0.4064 0)
			(stroke
				(width 0.2286)
				(type default)
			)
			(layer "B.SilkS")
		)
		(fp_rect
			(start 0.635 1.1811)
			(end -0.635 -1.1811)
			(stroke
				(width 0)
				(type default)
			)
			(fill no)
			(layer "B.CrtYd")
		)
		(fp_rect
			(start 0.635 1.1811)
			(end -0.635 -1.1811)
			(stroke
				(width 0)
				(type default)
			)
			(fill no)
			(layer "B.Fab")
		)
		(pad "1" smd custom
			(at 0 -0.6604 180)
			(size 0.19685 0.19685)
			(layers "B.Cu" "B.Mask" "B.Paste")
			(net "GND")
			(options
				(clearance outline)
				(anchor circle)
			)
			(primitives
				(gr_poly
					(pts
						(arc
							(start 0.508 0.2921)
							(mid 0.478242 0.363942)
							(end 0.4064 0.3937)
						)
						(arc
							(start -0.4064 0.3937)
							(mid -0.478242 0.363942)
							(end -0.508 0.2921)
						)
						(arc
							(start -0.508 -0.2921)
							(mid -0.478242 -0.363942)
							(end -0.4064 -0.3937)
						)
						(arc
							(start 0.4064 -0.3937)
							(mid 0.478242 -0.363942)
							(end 0.508 -0.2921)
						)
					)
					(width 0)
					(fill yes)
				)
			)
		)
		(pad "2" smd custom
			(at 0 0.6604 180)
			(size 0.19685 0.19685)
			(layers "B.Cu" "B.Mask" "B.Paste")
			(net "PV_VTT_DDR_B")
			(options
				(clearance outline)
				(anchor circle)
			)
			(primitives
				(gr_poly
					(pts
						(arc
							(start 0.508 0.2921)
							(mid 0.478242 0.363942)
							(end 0.4064 0.3937)
						)
						(arc
							(start -0.4064 0.3937)
							(mid -0.478242 0.363942)
							(end -0.508 0.2921)
						)
						(arc
							(start -0.508 -0.2921)
							(mid -0.478242 -0.363942)
							(end -0.4064 -0.3937)
						)
						(arc
							(start 0.4064 -0.3937)
							(mid 0.478242 -0.363942)
							(end 0.508 -0.2921)
						)
					)
					(width 0)
					(fill yes)
				)
			)
		)
	)
	(footprint ""
		(layer "B.Cu")
		(at 87.884 -22.479 -90)
		(property "Reference" "C254"
			(at 0 0 90)
			(layer "B.SilkS")
			(hide yes)
			(effects
				(font
					(size 1.27 1.27)
				)
				(justify mirror)
			)
		)
		(property "Value" "SC1U10V2KX-1GP"
			(at -1.1811 -2.7051 270)
			(unlocked yes)
			(layer "B.Fab")
			(hide yes)
			(effects
				(font
					(size 1.016 1.016)
					(thickness 0.1524)
				)
				(justify mirror)
			)
		)
		(property "Device Type" "C402H22"
			(at -1.1811 -4.2291 270)
			(unlocked yes)
			(layer "B.Fab")
			(hide yes)
			(effects
				(font
					(size 1.016 1.016)
					(thickness 0.1524)
				)
				(justify mirror)
			)
		)
		(duplicate_pad_numbers_are_jumpers no)
		(fp_rect
			(start 0.381 0.7366)
			(end -0.381 -0.7366)
			(stroke
				(width 0)
				(type default)
			)
			(fill no)
			(layer "B.CrtYd")
		)
		(fp_rect
			(start 0.381 0.7366)
			(end -0.381 -0.7366)
			(stroke
				(width 0)
				(type default)
			)
			(fill no)
			(layer "B.Fab")
		)
		(pad "1" smd custom
			(at 0 -0.4572 90)
			(size 0.1143 0.1143)
			(layers "B.Cu" "B.Mask" "B.Paste")
			(net "P1V0")
			(options
				(clearance outline)
				(anchor circle)
			)
			(primitives
				(gr_poly
					(pts
						(arc
							(start -0.254 0.1778)
							(mid -0.239121 0.213721)
							(end -0.2032 0.2286)
						)
						(arc
							(start 0.2032 0.2286)
							(mid 0.239121 0.213721)
							(end 0.254 0.1778)
						)
						(arc
							(start 0.254 -0.1778)
							(mid 0.239121 -0.213721)
							(end 0.2032 -0.2286)
						)
						(arc
							(start -0.2032 -0.2286)
							(mid -0.239121 -0.213721)
							(end -0.254 -0.1778)
						)
					)
					(width 0)
					(fill yes)
				)
			)
		)
		(pad "2" smd custom
			(at 0 0.4572 90)
			(size 0.1143 0.1143)
			(layers "B.Cu" "B.Mask" "B.Paste")
			(net "GND")
			(options
				(clearance outline)
				(anchor circle)
			)
			(primitives
				(gr_poly
					(pts
						(arc
							(start -0.254 0.1778)
							(mid -0.239121 0.213721)
							(end -0.2032 0.2286)
						)
						(arc
							(start 0.2032 0.2286)
							(mid 0.239121 0.213721)
							(end 0.254 0.1778)
						)
						(arc
							(start 0.254 -0.1778)
							(mid 0.239121 -0.213721)
							(end 0.2032 -0.2286)
						)
						(arc
							(start -0.2032 -0.2286)
							(mid -0.239121 -0.213721)
							(end -0.254 -0.1778)
						)
					)
					(width 0)
					(fill yes)
				)
			)
		)
	)
	(footprint ""
		(layer "B.Cu")
		(at 197.993 -41.148 -90)
		(property "Reference" "R153"
			(at 0 0 90)
			(layer "B.SilkS")
			(hide yes)
			(effects
				(font
					(size 1.27 1.27)
				)
				(justify mirror)
			)
		)
		(property "Value" "300R2F-GP"
			(at -0.064008 -3.993896 270)
			(unlocked yes)
			(layer "B.Fab")
			(hide yes)
			(effects
				(font
					(size 1.016 1.016)
					(thickness 0.1524)
				)
				(justify mirror)
			)
		)
		(property "Device Type" "R402H16"
			(at -0.064008 -5.517896 270)
			(unlocked yes)
			(layer "B.Fab")
			(hide yes)
			(effects
				(font
					(size 1.016 1.016)
					(thickness 0.1524)
				)
				(justify mirror)
			)
		)
		(duplicate_pad_numbers_are_jumpers no)
		(fp_rect
			(start 0.381 0.8382)
			(end -0.381 -0.8382)
			(stroke
				(width 0)
				(type default)
			)
			(fill no)
			(layer "B.CrtYd")
		)
		(fp_rect
			(start 0.381 0.8382)
			(end -0.381 -0.8382)
			(stroke
				(width 0)
				(type default)
			)
			(fill no)
			(layer "B.Fab")
		)
		(pad "1" smd custom
			(at 0 -0.4318 90)
			(size 0.127 0.127)
			(layers "B.Cu" "B.Mask" "B.Paste")
			(net "PORT80_R_BIT4")
			(options
				(clearance outline)
				(anchor circle)
			)
			(primitives
				(gr_poly
					(pts
						(arc
							(start -0.2032 0.2794)
							(mid -0.239121 0.264521)
							(end -0.254 0.2286)
						)
						(arc
							(start -0.254 -0.2286)
							(mid -0.239121 -0.264521)
							(end -0.2032 -0.2794)
						)
						(arc
							(start 0.2032 -0.2794)
							(mid 0.239121 -0.264521)
							(end 0.254 -0.2286)
						)
						(arc
							(start 0.254 0.2286)
							(mid 0.239121 0.264521)
							(end 0.2032 0.2794)
						)
					)
					(width 0)
					(fill yes)
				)
			)
		)
		(pad "2" smd custom
			(at 0 0.4318 90)
			(size 0.127 0.127)
			(layers "B.Cu" "B.Mask" "B.Paste")
			(net "P3V3_STBY")
			(options
				(clearance outline)
				(anchor circle)
			)
			(primitives
				(gr_poly
					(pts
						(arc
							(start -0.2032 0.2794)
							(mid -0.239121 0.264521)
							(end -0.254 0.2286)
						)
						(arc
							(start -0.254 -0.2286)
							(mid -0.239121 -0.264521)
							(end -0.2032 -0.2794)
						)
						(arc
							(start 0.2032 -0.2794)
							(mid 0.239121 -0.264521)
							(end 0.254 -0.2286)
						)
						(arc
							(start 0.254 0.2286)
							(mid 0.239121 0.264521)
							(end 0.2032 0.2794)
						)
					)
					(width 0)
					(fill yes)
				)
			)
		)
	)
)
